# BASEBOARD_FAB2 (Tioga Pass) — schematic netlist excerpt (pin names and nets, part order shuffled) for the footprints in the layout excerpt that follows; sources: Cadence DE-HDL packaged netlist, KiCad conversion of Wiwynn_Tioga_Pass_MB.brd

C2P9  CAP_A  0.1UF 16V 10% X7R  pkg 0402V  page 185 : A = P3V3_STBY ; B = GND
R1U14  RES  51 5.0% CHIP  pkg 0402  page 144 : A = SGPIO_BMC_CLK_R ; B = SGPIO_BMC_CLK
R1D23  RES  10.0K 1% CHIP  pkg 0402  page 200 : A = P3V3_STBY ; B = IRQ_OC_DETECT_N

(kicad_pcb
	(version 20260206)
	(generator "pcbnew")
	(generator_version "10.0")
	(general
		(thickness 1.6)
		(legacy_teardrops no)
	)
	(paper "A4")
	(title_block
		(title "Wiwynn_Tioga_Pass_MB.brd")
		(comment 1 "Tioga Pass / footprints 1257-1259 of 4770")
	)
	(layers
		(0 "F.Cu" signal "TOP")
		(4 "In1.Cu" signal "L2GND")
		(6 "In2.Cu" signal "L3")
		(8 "In3.Cu" signal "L4GND")
		(10 "In4.Cu" signal "L5")
		(12 "In5.Cu" signal "L6GND")
		(14 "In6.Cu" signal "L7VCC")
		(16 "In7.Cu" signal "L8VCC")
		(18 "In8.Cu" signal "L9GND")
		(20 "In9.Cu" signal "L10")
		(22 "In10.Cu" signal "L11GND")
		(24 "In11.Cu" signal "L12")
		(26 "In12.Cu" signal "L13GND")
		(2 "B.Cu" signal "BOTTOM")
		(9 "F.Adhes" user "F.Adhesive")
		(11 "B.Adhes" user "B.Adhesive")
		(13 "F.Paste" user "Package Geometry/Pastemask Top")
		(15 "B.Paste" user "Package Geometry/Pastemask Bottom")
		(5 "F.SilkS" user "Ref Des/Silkscreen Top")
		(7 "B.SilkS" user "Ref Des/Silkscreen Bottom")
		(1 "F.Mask" user "Board Geometry/Soldermask Top")
		(3 "B.Mask" user "Board Geometry/Soldermask Bottom")
		(17 "Dwgs.User" user "User.Drawings")
		(19 "Cmts.User" user "User.Comments")
		(21 "Eco1.User" user "User.Eco1")
		(23 "Eco2.User" user "User.Eco2")
		(25 "Edge.Cuts" user "Board Geometry/Outline")
		(27 "Margin" user)
		(31 "F.CrtYd" user "Package Geometry/Place Bound Top")
		(29 "B.CrtYd" user "Package Geometry/Place Bound Bottom")
		(35 "F.Fab" user "Ref Des/Assembly Top")
		(33 "B.Fab" user "Ref Des/Assembly Bottom")
	)
	(footprint ""
		(layer "F.Cu")
		(at 420.751 -22.733)
		(property "Reference" "R1U14"
			(at 0 0 0)
			(layer "F.SilkS")
			(hide yes)
			(effects
				(font
					(size 1.27 1.27)
				)
			)
		)
		(property "Value" ""
			(at 0 0 0)
			(layer "F.Fab")
			(effects
				(font
					(size 1.27 1.27)
				)
			)
		)
		(duplicate_pad_numbers_are_jumpers no)
		(fp_poly
			(pts
				(xy -0.2794 -0.1016) (xy 0.2794 -0.1016) (xy 0.2794 0.9906) (xy -0.2794 0.9906)
			)
			(stroke
				(width 0)
				(type default)
			)
			(fill no)
			(layer "F.CrtYd")
		)
		(fp_line
			(start -0.2794 -0.1016)
			(end -0.2794 0.9906)
			(stroke
				(width 0.1)
				(type default)
			)
			(layer "F.Fab")
		)
		(fp_line
			(start -0.2794 0.9906)
			(end 0.2794 0.9906)
			(stroke
				(width 0.1)
				(type default)
			)
			(layer "F.Fab")
		)
		(fp_line
			(start 0.2794 -0.1016)
			(end -0.2794 -0.1016)
			(stroke
				(width 0.1)
				(type default)
			)
			(layer "F.Fab")
		)
		(fp_line
			(start 0.2794 0.9906)
			(end 0.2794 -0.1016)
			(stroke
				(width 0.1)
				(type default)
			)
			(layer "F.Fab")
		)
		(pad "1" smd rect
			(at 0 0)
			(size 0.508 0.508)
			(layers "F.Cu" "F.Mask" "F.Paste")
			(net "SGPIO_BMC_CLK_R")
		)
		(pad "2" smd rect
			(at 0 0.889)
			(size 0.508 0.508)
			(layers "F.Cu" "F.Mask" "F.Paste")
			(net "SGPIO_BMC_CLK")
		)
		(zone
			(layer "F.Cu")
			(hatch none 0.5)
			(connect_pads
				(clearance 0)
			)
			(min_thickness 0.25)
			(keepout
				(tracks allowed)
				(vias not_allowed)
				(pads allowed)
				(copperpour not_allowed)
				(footprints allowed)
			)
			(placement
				(enabled no)
				(sheetname "")
			)
			(fill
				(thermal_gap 0.5)
				(thermal_bridge_width 0.5)
				(island_removal_mode 0)
			)
			(polygon
				(pts
					(xy 420.497 -22.479) (xy 421.005 -22.479) (xy 421.005 -22.098) (xy 420.497 -22.098)
				)
			)
		)
		(zone
			(layer "F.Cu")
			(hatch none 0.5)
			(connect_pads
				(clearance 0)
			)
			(min_thickness 0.25)
			(keepout
				(tracks not_allowed)
				(vias allowed)
				(pads allowed)
				(copperpour not_allowed)
				(footprints allowed)
			)
			(placement
				(enabled no)
				(sheetname "")
			)
			(fill
				(thermal_gap 0.5)
				(thermal_bridge_width 0.5)
				(island_removal_mode 0)
			)
			(polygon
				(pts
					(xy 420.497 -22.098) (xy 421.005 -22.098) (xy 421.005 -22.479) (xy 420.497 -22.479)
				)
			)
		)
	)
	(footprint ""
		(layer "F.Cu")
		(at 20.447 -80.90408 180)
		(property "Reference" "R1D23"
			(at 0 0 180)
			(layer "F.SilkS")
			(hide yes)
			(effects
				(font
					(size 1.27 1.27)
				)
			)
		)
		(property "Value" ""
			(at 0 0 180)
			(layer "F.Fab")
			(effects
				(font
					(size 1.27 1.27)
				)
			)
		)
		(duplicate_pad_numbers_are_jumpers no)
		(fp_poly
			(pts
				(xy -0.2794 -0.1016) (xy 0.2794 -0.1016) (xy 0.2794 0.9906) (xy -0.2794 0.9906)
			)
			(stroke
				(width 0)
				(type default)
			)
			(fill no)
			(layer "F.CrtYd")
		)
		(fp_line
			(start 0.2794 0.9906)
			(end 0.2794 -0.1016)
			(stroke
				(width 0.1)
				(type default)
			)
			(layer "F.Fab")
		)
		(fp_line
			(start 0.2794 -0.1016)
			(end -0.2794 -0.1016)
			(stroke
				(width 0.1)
				(type default)
			)
			(layer "F.Fab")
		)
		(fp_line
			(start -0.2794 0.9906)
			(end 0.2794 0.9906)
			(stroke
				(width 0.1)
				(type default)
			)
			(layer "F.Fab")
		)
		(fp_line
			(start -0.2794 -0.1016)
			(end -0.2794 0.9906)
			(stroke
				(width 0.1)
				(type default)
			)
			(layer "F.Fab")
		)
		(pad "1" smd rect
			(at 0 0 180)
			(size 0.508 0.508)
			(layers "F.Cu" "F.Mask" "F.Paste")
			(net "P3V3_STBY")
		)
		(pad "2" smd rect
			(at 0 0.889 180)
			(size 0.508 0.508)
			(layers "F.Cu" "F.Mask" "F.Paste")
			(net "IRQ_OC_DETECT_N")
		)
		(zone
			(layer "F.Cu")
			(hatch none 0.5)
			(connect_pads
				(clearance 0)
			)
			(min_thickness 0.25)
			(keepout
				(tracks not_allowed)
				(vias allowed)
				(pads allowed)
				(copperpour not_allowed)
				(footprints allowed)
			)
			(placement
				(enabled no)
				(sheetname "")
			)
			(fill
				(thermal_gap 0.5)
				(thermal_bridge_width 0.5)
				(island_removal_mode 0)
			)
			(polygon
				(pts
					(xy 20.701 -81.53908) (xy 20.193 -81.53908) (xy 20.193 -81.15808) (xy 20.701 -81.15808)
				)
			)
		)
		(zone
			(layer "F.Cu")
			(hatch none 0.5)
			(connect_pads
				(clearance 0)
			)
			(min_thickness 0.25)
			(keepout
				(tracks allowed)
				(vias not_allowed)
				(pads allowed)
				(copperpour not_allowed)
				(footprints allowed)
			)
			(placement
				(enabled no)
				(sheetname "")
			)
			(fill
				(thermal_gap 0.5)
				(thermal_bridge_width 0.5)
				(island_removal_mode 0)
			)
			(polygon
				(pts
					(xy 20.701 -81.15808) (xy 20.193 -81.15808) (xy 20.193 -81.53908) (xy 20.701 -81.53908)
				)
			)
		)
	)
	(footprint ""
		(layer "F.Cu")
		(at 403.112986 -81.548986 -90)
		(property "Reference" "C2P9"
			(at 0 0 270)
			(layer "F.SilkS")
			(hide yes)
			(effects
				(font
					(size 1.27 1.27)
				)
			)
		)
		(property "Value" ""
			(at 0 0 270)
			(layer "F.Fab")
			(effects
				(font
					(size 1.27 1.27)
				)
			)
		)
		(duplicate_pad_numbers_are_jumpers no)
		(fp_poly
			(pts
				(xy 0.3048 -0.1016) (xy 0.3048 0.9906) (xy -0.3048 0.9906) (xy -0.3048 -0.1016)
			)
			(stroke
				(width 0)
				(type default)
			)
			(fill no)
			(layer "F.CrtYd")
		)
		(fp_line
			(start -0.3048 0.9906)
			(end 0.3048 0.9906)
			(stroke
				(width 0.1)
				(type default)
			)
			(layer "F.Fab")
		)
		(fp_line
			(start 0.3048 0.9906)
			(end 0.3048 -0.1016)
			(stroke
				(width 0.1)
				(type default)
			)
			(layer "F.Fab")
		)
		(fp_line
			(start -0.3048 -0.1016)
			(end -0.3048 0.9906)
			(stroke
				(width 0.1)
				(type default)
			)
			(layer "F.Fab")
		)
		(fp_line
			(start 0.3048 -0.1016)
			(end -0.3048 -0.1016)
			(stroke
				(width 0.1)
				(type default)
			)
			(layer "F.Fab")
		)
		(pad "1" smd rect
			(at 0 0 270)
			(size 0.508 0.508)
			(layers "F.Cu" "F.Mask" "F.Paste")
			(net "P3V3_STBY")
		)
		(pad "2" smd rect
			(at 0 0.889 270)
			(size 0.508 0.508)
			(layers "F.Cu" "F.Mask" "F.Paste")
			(net "GND")
		)
		(zone
			(layer "F.Cu")
			(hatch none 0.5)
			(connect_pads
				(clearance 0)
			)
			(min_thickness 0.25)
			(keepout
				(tracks not_allowed)
				(vias allowed)
				(pads allowed)
				(copperpour not_allowed)
				(footprints allowed)
			)
			(placement
				(enabled no)
				(sheetname "")
			)
			(fill
				(thermal_gap 0.5)
				(thermal_bridge_width 0.5)
				(island_removal_mode 0)
			)
			(polygon
				(pts
					(xy 402.477986 -81.802986) (xy 402.477986 -81.294986) (xy 402.858986 -81.294986) (xy 402.858986 -81.802986)
				)
			)
		)
		(zone
			(layer "F.Cu")
			(hatch none 0.5)
			(connect_pads
				(clearance 0)
			)
			(min_thickness 0.25)
			(keepout
				(tracks allowed)
				(vias not_allowed)
				(pads allowed)
				(copperpour not_allowed)
				(footprints allowed)
			)
			(placement
				(enabled no)
				(sheetname "")
			)
			(fill
				(thermal_gap 0.5)
				(thermal_bridge_width 0.5)
				(island_removal_mode 0)
			)
			(polygon
				(pts
					(xy 402.858986 -81.802986) (xy 402.858986 -81.294986) (xy 402.477986 -81.294986) (xy 402.477986 -81.802986)
				)
			)
		)
	)
)
